(kicad_pcb
	(version 20260206)
	(generator "pcbnew")
	(generator_version "10.0")
	(general
		(thickness 1.6)
		(legacy_teardrops no)
	)
	(paper "A4")
	(title_block
		(title "Bryce Canyon_R.DPB_16317-1_OCP.brd")
		(comment 1 "Bryce Canyon / footprints 1211-1216 of 2099")
	)
	(layers
		(0 "F.Cu" signal "TOP")
		(4 "In1.Cu" signal "L2GND")
		(6 "In2.Cu" signal "L3")
		(8 "In3.Cu" signal "L4VCC")
		(10 "In4.Cu" signal "L5VCC")
		(12 "In5.Cu" signal "L6")
		(14 "In6.Cu" signal "L7GND")
		(2 "B.Cu" signal "BOTTOM")
		(9 "F.Adhes" user "F.Adhesive")
		(11 "B.Adhes" user "B.Adhesive")
		(13 "F.Paste" user "Package Geometry/Pastemask Top")
		(15 "B.Paste" user "Package Geometry/Pastemask Bottom")
		(5 "F.SilkS" user "Ref Des/Silkscreen Top")
		(7 "B.SilkS" user "Ref Des/Silkscreen Bottom")
		(1 "F.Mask" user "Board Geometry/Soldermask Top")
		(3 "B.Mask" user "Board Geometry/Soldermask Bottom")
		(17 "Dwgs.User" user "User.Drawings")
		(19 "Cmts.User" user "User.Comments")
		(21 "Eco1.User" user "User.Eco1")
		(23 "Eco2.User" user "User.Eco2")
		(25 "Edge.Cuts" user "Board Geometry/Outline")
		(27 "Margin" user)
		(31 "F.CrtYd" user "Package Geometry/Place Bound Top")
		(29 "B.CrtYd" user "Package Geometry/Place Bound Bottom")
		(35 "F.Fab" user "Ref Des/Assembly Top")
		(33 "B.Fab" user "Ref Des/Assembly Bottom")
	)
	(footprint ""
		(layer "F.Cu")
		(at 146.4564 -33.782 -90)
		(property "Reference" "C394"
			(at 0 0 270)
			(layer "F.SilkS")
			(hide yes)
			(effects
				(font
					(size 1.27 1.27)
				)
			)
		)
		(property "Value" "SC1U16V3KX-5GP"
			(at 0 -2.8194 270)
			(unlocked yes)
			(layer "F.Fab")
			(hide yes)
			(effects
				(font
					(size 1.016 1.016)
					(thickness 0.1524)
				)
			)
		)
		(property "Device Type" "C603H36"
			(at 0 -4.3434 270)
			(unlocked yes)
			(layer "F.Fab")
			(hide yes)
			(effects
				(font
					(size 1.016 1.016)
					(thickness 0.1524)
				)
			)
		)
		(duplicate_pad_numbers_are_jumpers no)
		(fp_line
			(start 0.508 0)
			(end -0.508 0)
			(stroke
				(width 0.2032)
				(type default)
			)
			(layer "F.SilkS")
		)
		(fp_rect
			(start -0.5842 1.3335)
			(end 0.5842 -1.3335)
			(stroke
				(width 0)
				(type default)
			)
			(fill no)
			(layer "F.CrtYd")
		)
		(fp_rect
			(start -0.5842 1.3335)
			(end 0.5842 -1.3335)
			(stroke
				(width 0)
				(type default)
			)
			(fill no)
			(layer "F.Fab")
		)
		(pad "1" smd custom
			(at 0 -0.762 270)
			(size 0.2159 0.2159)
			(layers "F.Cu" "F.Mask" "F.Paste")
			(net "P5V_HDD28")
			(options
				(clearance outline)
				(anchor circle)
			)
			(primitives
				(gr_poly
					(pts
						(arc
							(start -0.3302 -0.4318)
							(mid -0.402042 -0.402042)
							(end -0.4318 -0.3302)
						)
						(arc
							(start -0.4318 0.3302)
							(mid -0.402042 0.402042)
							(end -0.3302 0.4318)
						)
						(arc
							(start 0.3302 0.4318)
							(mid 0.402042 0.402042)
							(end 0.4318 0.3302)
						)
						(arc
							(start 0.4318 -0.3302)
							(mid 0.402042 -0.402042)
							(end 0.3302 -0.4318)
						)
					)
					(width 0)
					(fill yes)
				)
			)
		)
		(pad "2" smd custom
			(at 0 0.762 270)
			(size 0.2159 0.2159)
			(layers "F.Cu" "F.Mask" "F.Paste")
			(net "GND")
			(options
				(clearance outline)
				(anchor circle)
			)
			(primitives
				(gr_poly
					(pts
						(arc
							(start -0.3302 -0.4318)
							(mid -0.402042 -0.402042)
							(end -0.4318 -0.3302)
						)
						(arc
							(start -0.4318 0.3302)
							(mid -0.402042 0.402042)
							(end -0.3302 0.4318)
						)
						(arc
							(start 0.3302 0.4318)
							(mid 0.402042 0.402042)
							(end 0.4318 0.3302)
						)
						(arc
							(start 0.4318 -0.3302)
							(mid 0.402042 -0.402042)
							(end 0.3302 -0.4318)
						)
					)
					(width 0)
					(fill yes)
				)
			)
		)
	)
	(footprint ""
		(layer "F.Cu")
		(at 334.899 -138.938 -90)
		(property "Reference" "Q82"
			(at 0 0 270)
			(layer "F.SilkS")
			(hide yes)
			(effects
				(font
					(size 1.27 1.27)
				)
			)
		)
		(property "Value" "AO4406AL-GP"
			(at -3.707384 -1.5367 270)
			(unlocked yes)
			(layer "F.Fab")
			(hide yes)
			(effects
				(font
					(size 1.016 1.016)
					(thickness 0.1524)
				)
			)
		)
		(property "Device Type" "SOIC8H69"
			(at -3.707384 -3.0607 270)
			(unlocked yes)
			(layer "F.Fab")
			(hide yes)
			(effects
				(font
					(size 1.016 1.016)
					(thickness 0.1524)
				)
			)
		)
		(duplicate_pad_numbers_are_jumpers no)
		(fp_line
			(start -2.6289 3.4417)
			(end -2.6289 1.4732)
			(stroke
				(width 0.381)
				(type default)
			)
			(layer "F.SilkS")
		)
		(fp_line
			(start -2.7432 1.4224)
			(end -2.6416 1.4224)
			(stroke
				(width 0.1524)
				(type default)
			)
			(layer "F.SilkS")
		)
		(fp_line
			(start -2.7432 1.4224)
			(end 2.1336 1.4224)
			(stroke
				(width 0.1524)
				(type default)
			)
			(layer "F.SilkS")
		)
		(fp_line
			(start 2.1336 1.4224)
			(end 2.1336 -1.4224)
			(stroke
				(width 0.1524)
				(type default)
			)
			(layer "F.SilkS")
		)
		(fp_line
			(start -2.1844 -0.0508)
			(end -2.7178 0.508)
			(stroke
				(width 0.1524)
				(type default)
			)
			(layer "F.SilkS")
		)
		(fp_line
			(start -2.7178 -0.508)
			(end -2.1844 -0.0508)
			(stroke
				(width 0.1524)
				(type default)
			)
			(layer "F.SilkS")
		)
		(fp_line
			(start -2.7432 -1.4224)
			(end -2.7432 1.4224)
			(stroke
				(width 0.1524)
				(type default)
			)
			(layer "F.SilkS")
		)
		(fp_line
			(start 2.1336 -1.4224)
			(end -2.7432 -1.4224)
			(stroke
				(width 0.1524)
				(type default)
			)
			(layer "F.SilkS")
		)
		(fp_poly
			(pts
				(xy -2.2098 -1.4224) (xy -2.2098 1.4224) (xy 2.2098 1.4224) (xy 2.2098 -1.4224)
			)
			(stroke
				(width 0)
				(type default)
			)
			(fill yes)
			(layer "F.SilkS")
		)
		(fp_rect
			(start -2.450084 2.999994)
			(end 2.450084 -2.999994)
			(stroke
				(width 0)
				(type default)
			)
			(fill no)
			(layer "F.CrtYd")
		)
		(fp_poly
			(pts
				(xy -2.8194 3.6322) (xy -2.8194 -3.6322) (xy 2.8194 -3.6322) (xy 2.8194 1.18364) (xy 2.450084 1.18364)
				(xy 2.450084 -2.999994) (xy -2.450084 -2.999994) (xy -2.450084 2.999994) (xy 2.450084 2.999994)
				(xy 2.450084 1.18618) (xy 2.8194 1.18618) (xy 2.8194 3.6322)
			)
			(stroke
				(width 0)
				(type default)
			)
			(fill no)
			(layer "F.CrtYd")
		)
		(fp_rect
			(start -2.8194 3.6322)
			(end 2.8194 -3.6322)
			(stroke
				(width 0)
				(type default)
			)
			(fill no)
			(layer "F.Fab")
		)
		(pad "1" smd rect
			(at -1.905 2.54 270)
			(size 0.635 1.651)
			(layers "F.Cu" "F.Mask" "F.Paste")
			(net "P5V_HDD18")
		)
		(pad "2" smd rect
			(at -0.635 2.54 270)
			(size 0.635 1.651)
			(layers "F.Cu" "F.Mask" "F.Paste")
			(net "P5V_HDD18")
		)
		(pad "3" smd rect
			(at 0.635 2.54 270)
			(size 0.635 1.651)
			(layers "F.Cu" "F.Mask" "F.Paste")
			(net "P5V_HDD18")
		)
		(pad "4" smd rect
			(at 1.905 2.54 270)
			(size 0.635 1.651)
			(layers "F.Cu" "F.Mask" "F.Paste")
			(net "SW_HDD_P18")
		)
		(pad "5" smd rect
			(at 1.905 -2.54 270)
			(size 0.635 1.651)
			(layers "F.Cu" "F.Mask" "F.Paste")
			(net "P5V_B_3")
		)
		(pad "6" smd rect
			(at 0.635 -2.54 270)
			(size 0.635 1.651)
			(layers "F.Cu" "F.Mask" "F.Paste")
			(net "P5V_B_3")
		)
		(pad "7" smd rect
			(at -0.635 -2.54 270)
			(size 0.635 1.651)
			(layers "F.Cu" "F.Mask" "F.Paste")
			(net "P5V_B_3")
		)
		(pad "8" smd rect
			(at -1.905 -2.54 270)
			(size 0.635 1.651)
			(layers "F.Cu" "F.Mask" "F.Paste")
			(net "P5V_B_3")
		)
	)
	(footprint ""
		(layer "F.Cu")
		(at 444.929768 -102.26802 -90)
		(property "Reference" "R486"
			(at 0 0 270)
			(layer "F.SilkS")
			(hide yes)
			(effects
				(font
					(size 1.27 1.27)
				)
			)
		)
		(property "Value" "4K7R2F-GP"
			(at 0.064008 -3.993896 270)
			(unlocked yes)
			(layer "F.Fab")
			(hide yes)
			(effects
				(font
					(size 1.016 1.016)
					(thickness 0.1524)
				)
			)
		)
		(property "Device Type" "R402H16"
			(at 0.064008 -5.517896 270)
			(unlocked yes)
			(layer "F.Fab")
			(hide yes)
			(effects
				(font
					(size 1.016 1.016)
					(thickness 0.1524)
				)
			)
		)
		(duplicate_pad_numbers_are_jumpers no)
		(fp_line
			(start -0.508 -0.9398)
			(end -0.508 0.9398)
			(stroke
				(width 0.1524)
				(type default)
			)
			(layer "F.SilkS")
		)
		(fp_line
			(start 0.508 -0.9398)
			(end -0.508 -0.9398)
			(stroke
				(width 0.1524)
				(type default)
			)
			(layer "F.SilkS")
		)
		(fp_rect
			(start -0.508 0.9398)
			(end 0.508 -0.9398)
			(stroke
				(width 0)
				(type default)
			)
			(fill no)
			(layer "F.CrtYd")
		)
		(fp_rect
			(start -0.508 0.9398)
			(end 0.508 -0.9398)
			(stroke
				(width 0)
				(type default)
			)
			(fill no)
			(layer "F.Fab")
		)
		(pad "1" smd custom
			(at 0 -0.4445 270)
			(size 0.1397 0.1397)
			(layers "F.Cu" "F.Mask" "F.Paste")
			(net "DRIVE_B_22_ACT")
			(options
				(clearance outline)
				(anchor circle)
			)
			(primitives
				(gr_poly
					(pts
						(arc
							(start -0.1778 -0.2794)
							(mid -0.249642 -0.249642)
							(end -0.2794 -0.1778)
						)
						(arc
							(start -0.2794 0.1778)
							(mid -0.249642 0.249642)
							(end -0.1778 0.2794)
						)
						(arc
							(start 0.1778 0.2794)
							(mid 0.249642 0.249642)
							(end 0.2794 0.1778)
						)
						(arc
							(start 0.2794 -0.1778)
							(mid 0.249642 -0.249642)
							(end 0.1778 -0.2794)
						)
					)
					(width 0)
					(fill yes)
				)
			)
		)
		(pad "2" smd custom
			(at 0 0.4445 270)
			(size 0.1397 0.1397)
			(layers "F.Cu" "F.Mask" "F.Paste")
			(net "GND")
			(options
				(clearance outline)
				(anchor circle)
			)
			(primitives
				(gr_poly
					(pts
						(arc
							(start -0.1778 -0.2794)
							(mid -0.249642 -0.249642)
							(end -0.2794 -0.1778)
						)
						(arc
							(start -0.2794 0.1778)
							(mid -0.249642 0.249642)
							(end -0.1778 0.2794)
						)
						(arc
							(start 0.1778 0.2794)
							(mid 0.249642 0.249642)
							(end 0.2794 0.1778)
						)
						(arc
							(start 0.2794 -0.1778)
							(mid 0.249642 -0.249642)
							(end 0.1778 -0.2794)
						)
					)
					(width 0)
					(fill yes)
				)
			)
		)
	)
	(footprint ""
		(layer "F.Cu")
		(at 146.304 -262.001 -90)
		(property "Reference" "C83"
			(at 0 0 270)
			(layer "F.SilkS")
			(hide yes)
			(effects
				(font
					(size 1.27 1.27)
				)
			)
		)
		(property "Value" "SC10U16V6KX-2GP"
			(at -0.0762 -5.1308 270)
			(unlocked yes)
			(layer "F.Fab")
			(hide yes)
			(effects
				(font
					(size 1.016 1.016)
					(thickness 0.1524)
				)
			)
		)
		(property "Device Type" "C1206H71"
			(at -0.127 -6.6548 270)
			(unlocked yes)
			(layer "F.Fab")
			(hide yes)
			(effects
				(font
					(size 1.016 1.016)
					(thickness 0.1524)
				)
			)
		)
		(duplicate_pad_numbers_are_jumpers no)
		(fp_line
			(start -1.016 2.2352)
			(end -1.016 0.8382)
			(stroke
				(width 0.1524)
				(type default)
			)
			(layer "F.SilkS")
		)
		(fp_line
			(start 1.016 2.2352)
			(end -1.016 2.2352)
			(stroke
				(width 0.1524)
				(type default)
			)
			(layer "F.SilkS")
		)
		(fp_line
			(start 1.016 0.8382)
			(end 1.016 2.2352)
			(stroke
				(width 0.1524)
				(type default)
			)
			(layer "F.SilkS")
		)
		(fp_line
			(start -1.016 -0.8382)
			(end -1.016 -2.2352)
			(stroke
				(width 0.1524)
				(type default)
			)
			(layer "F.SilkS")
		)
		(fp_line
			(start -1.016 -2.2352)
			(end 1.016 -2.2352)
			(stroke
				(width 0.1524)
				(type default)
			)
			(layer "F.SilkS")
		)
		(fp_line
			(start 1.016 -2.2352)
			(end 1.016 -0.8382)
			(stroke
				(width 0.1524)
				(type default)
			)
			(layer "F.SilkS")
		)
		(fp_rect
			(start -1.0922 2.3114)
			(end 1.0922 -2.3114)
			(stroke
				(width 0)
				(type default)
			)
			(fill no)
			(layer "F.CrtYd")
		)
		(fp_poly
			(pts
				(xy 1.0922 -2.3114) (xy 1.0922 2.3114) (xy -1.0922 2.3114) (xy -1.0922 -2.3114)
			)
			(stroke
				(width 0)
				(type default)
			)
			(fill no)
			(layer "F.Fab")
		)
		(pad "1" smd rect
			(at 0 -1.397 270)
			(size 1.651 1.27)
			(layers "F.Cu" "F.Mask" "F.Paste")
			(net "P5V_HDD4")
		)
		(pad "2" smd rect
			(at 0 1.397 270)
			(size 1.651 1.27)
			(layers "F.Cu" "F.Mask" "F.Paste")
			(net "GND")
		)
	)
	(footprint ""
		(layer "F.Cu")
		(at 20.701 -26.289 180)
		(property "Reference" "Q118"
			(at 0 0 180)
			(layer "F.SilkS")
			(hide yes)
			(effects
				(font
					(size 1.27 1.27)
				)
			)
		)
		(property "Value" "AO4406AL-GP"
			(at -3.707384 -1.5367 180)
			(unlocked yes)
			(layer "F.Fab")
			(hide yes)
			(effects
				(font
					(size 1.016 1.016)
					(thickness 0.1524)
				)
			)
		)
		(property "Device Type" "SOIC8H69"
			(at -3.707384 -3.0607 180)
			(unlocked yes)
			(layer "F.Fab")
			(hide yes)
			(effects
				(font
					(size 1.016 1.016)
					(thickness 0.1524)
				)
			)
		)
		(duplicate_pad_numbers_are_jumpers no)
		(fp_line
			(start 2.1336 1.4224)
			(end 2.1336 -1.4224)
			(stroke
				(width 0.1524)
				(type default)
			)
			(layer "F.SilkS")
		)
		(fp_line
			(start 2.1336 -1.4224)
			(end -2.7432 -1.4224)
			(stroke
				(width 0.1524)
				(type default)
			)
			(layer "F.SilkS")
		)
		(fp_line
			(start -2.1844 -0.0508)
			(end -2.7178 0.508)
			(stroke
				(width 0.1524)
				(type default)
			)
			(layer "F.SilkS")
		)
		(fp_line
			(start -2.6289 3.4417)
			(end -2.6289 1.4732)
			(stroke
				(width 0.381)
				(type default)
			)
			(layer "F.SilkS")
		)
		(fp_line
			(start -2.7178 -0.508)
			(end -2.1844 -0.0508)
			(stroke
				(width 0.1524)
				(type default)
			)
			(layer "F.SilkS")
		)
		(fp_line
			(start -2.7432 1.4224)
			(end 2.1336 1.4224)
			(stroke
				(width 0.1524)
				(type default)
			)
			(layer "F.SilkS")
		)
		(fp_line
			(start -2.7432 1.4224)
			(end -2.6416 1.4224)
			(stroke
				(width 0.1524)
				(type default)
			)
			(layer "F.SilkS")
		)
		(fp_line
			(start -2.7432 -1.4224)
			(end -2.7432 1.4224)
			(stroke
				(width 0.1524)
				(type default)
			)
			(layer "F.SilkS")
		)
		(fp_poly
			(pts
				(xy -2.2098 -1.4224) (xy -2.2098 1.4224) (xy 2.2098 1.4224) (xy 2.2098 -1.4224)
			)
			(stroke
				(width 0)
				(type default)
			)
			(fill yes)
			(layer "F.SilkS")
		)
		(fp_rect
			(start -2.450084 2.999994)
			(end 2.450084 -2.999994)
			(stroke
				(width 0)
				(type default)
			)
			(fill no)
			(layer "F.CrtYd")
		)
		(fp_poly
			(pts
				(xy -2.8194 3.6322) (xy -2.8194 -3.6322) (xy 2.8194 -3.6322) (xy 2.8194 1.18364) (xy 2.450084 1.18364)
				(xy 2.450084 -2.999994) (xy -2.450084 -2.999994) (xy -2.450084 2.999994) (xy 2.450084 2.999994)
				(xy 2.450084 1.18618) (xy 2.8194 1.18618) (xy 2.8194 3.6322)
			)
			(stroke
				(width 0)
				(type default)
			)
			(fill no)
			(layer "F.CrtYd")
		)
		(fp_rect
			(start -2.8194 3.6322)
			(end 2.8194 -3.6322)
			(stroke
				(width 0)
				(type default)
			)
			(fill no)
			(layer "F.Fab")
		)
		(pad "1" smd rect
			(at -1.905 2.54 180)
			(size 0.635 1.651)
			(layers "F.Cu" "F.Mask" "F.Paste")
			(net "P5V_HDD24")
		)
		(pad "2" smd rect
			(at -0.635 2.54 180)
			(size 0.635 1.651)
			(layers "F.Cu" "F.Mask" "F.Paste")
			(net "P5V_HDD24")
		)
		(pad "3" smd rect
			(at 0.635 2.54 180)
			(size 0.635 1.651)
			(layers "F.Cu" "F.Mask" "F.Paste")
			(net "P5V_HDD24")
		)
		(pad "4" smd rect
			(at 1.905 2.54 180)
			(size 0.635 1.651)
			(layers "F.Cu" "F.Mask" "F.Paste")
			(net "SW_HDD_P24")
		)
		(pad "5" smd rect
			(at 1.905 -2.54 180)
			(size 0.635 1.651)
			(layers "F.Cu" "F.Mask" "F.Paste")
			(net "P5V_B_2")
		)
		(pad "6" smd rect
			(at 0.635 -2.54 180)
			(size 0.635 1.651)
			(layers "F.Cu" "F.Mask" "F.Paste")
			(net "P5V_B_2")
		)
		(pad "7" smd rect
			(at -0.635 -2.54 180)
			(size 0.635 1.651)
			(layers "F.Cu" "F.Mask" "F.Paste")
			(net "P5V_B_2")
		)
		(pad "8" smd rect
			(at -1.905 -2.54 180)
			(size 0.635 1.651)
			(layers "F.Cu" "F.Mask" "F.Paste")
			(net "P5V_B_2")
		)
	)
	(footprint ""
		(layer "F.Cu")
		(at 381.1778 -261.3152)
		(property "Reference" "R289"
			(at 0 0 0)
			(layer "F.SilkS")
			(hide yes)
			(effects
				(font
					(size 1.27 1.27)
				)
			)
		)
		(property "Value" "220R3F-1-GP"
			(at -0.0254 -2.5146 0)
			(unlocked yes)
			(layer "F.Fab")
			(hide yes)
			(effects
				(font
					(size 1.016 1.016)
					(thickness 0.1524)
				)
			)
		)
		(property "Device Type" "R603H22"
			(at -0.0254 -4.0386 0)
			(unlocked yes)
			(layer "F.Fab")
			(hide yes)
			(effects
				(font
					(size 1.016 1.016)
					(thickness 0.1524)
				)
			)
		)
		(duplicate_pad_numbers_are_jumpers no)
		(fp_line
			(start -0.4826 0)
			(end -0.2032 0)
			(stroke
				(width 0.2032)
				(type default)
			)
			(layer "F.SilkS")
		)
		(fp_line
			(start 0.2032 0)
			(end 0.4826 0)
			(stroke
				(width 0.2032)
				(type default)
			)
			(layer "F.SilkS")
		)
		(fp_rect
			(start -0.5842 1.3335)
			(end 0.5842 -1.3335)
			(stroke
				(width 0)
				(type default)
			)
			(fill no)
			(layer "F.CrtYd")
		)
		(fp_rect
			(start -0.5842 1.3335)
			(end 0.5842 -1.3335)
			(stroke
				(width 0)
				(type default)
			)
			(fill no)
			(layer "F.Fab")
		)
		(pad "1" smd custom
			(at 0 -0.762)
			(size 0.2159 0.2159)
			(layers "F.Cu" "F.Mask" "F.Paste")
			(net "HDD_PRSNT_8")
			(options
				(clearance outline)
				(anchor circle)
			)
			(primitives
				(gr_poly
					(pts
						(arc
							(start -0.3302 -0.4318)
							(mid -0.402042 -0.402042)
							(end -0.4318 -0.3302)
						)
						(arc
							(start -0.4318 0.3302)
							(mid -0.402042 0.402042)
							(end -0.3302 0.4318)
						)
						(arc
							(start 0.3302 0.4318)
							(mid 0.402042 0.402042)
							(end 0.4318 0.3302)
						)
						(arc
							(start 0.4318 -0.3302)
							(mid 0.402042 -0.402042)
							(end 0.3302 -0.4318)
						)
					)
					(width 0)
					(fill yes)
				)
			)
		)
		(pad "2" smd custom
			(at 0 0.762)
			(size 0.2159 0.2159)
			(layers "F.Cu" "F.Mask" "F.Paste")
			(net "DRIVE_B_8_INS")
			(options
				(clearance outline)
				(anchor circle)
			)
			(primitives
				(gr_poly
					(pts
						(arc
							(start -0.3302 -0.4318)
							(mid -0.402042 -0.402042)
							(end -0.4318 -0.3302)
						)
						(arc
							(start -0.4318 0.3302)
							(mid -0.402042 0.402042)
							(end -0.3302 0.4318)
						)
						(arc
							(start 0.3302 0.4318)
							(mid 0.402042 0.402042)
							(end 0.4318 0.3302)
						)
						(arc
							(start 0.4318 -0.3302)
							(mid 0.402042 -0.402042)
							(end 0.3302 -0.4318)
						)
					)
					(width 0)
					(fill yes)
				)
			)
		)
	)
)
